# Primary and Alternate BOM of B91.01110.0010_SCC wo IOC.xls — Sheet0 (bom)
| Part Number | B91.01110.0010 |  |  |  |  |  |  |  |  |  |  |  |  |
| Revision | E |  |  |  |  |  |  |  |  |  |  |  |  |
| Sequence | 1 |  |  |  |  |  |  |  |  |  |  |  |  |
| Description | BRYCECANYON 19-000791-3 SCC W/O IOC SP P |  |  |  |  |  |  |  |  |  |  |  |  |
| Project Code | BPD011010001 |  |  |  |  |  |  |  |  |  |  |  |  |
| Latest Revision? | YES |  |  |  |  |  |  |  |  |  |  |  |  |
| PDM BOM List |  |  |  |  |  |  |  |  |  |  |  |  |  |
| Level | Parent Number | Part Number | Description | Green Factor | Manufacturer | Manufacturer Part Number | Source | BOM Usage | M/P Code | S/D | Qty | UoM | Location |
| 1 | B91.01110.0010 | B55.01102.0004 | BRYCE CANYON SCC W/O IOC GCE-1 P MAIN(D) | R2; |  |  |  | M | Manufacture |  | 1 | PCS |  |
| 2 | B55.01102.0004 | 020.80777.0001 | CONN PWR XCEDE JX310-50387_REVB | R2_SA;HF_SA; | AMPHENOL | JX310-50387 | Single |  | Purchase | DIP | 1 | PCS | CN1 |
| 2 | B55.01102.0004 | 020.80963.0001 | CONN SIGNAL XCEDE JX310-50375_REVC | R2_SA; | AMPHENOL | JX310-50375_RevC | Single |  | Purchase | DIP | 1 | PCS | CN2 |
| 2 | B55.01102.0004 | 20.82057.036 | CONN CTR IPASS 36P 76867-1011 PRESSFIT | R2_SA;HF_SA; | MOLEX | 76867-1011 | Multiple |  | Purchase | DIP | 1 | PCS | MSAS1 |
| A(Alternative to previous component) | B55.01102.0004 | 20.82058.036 | CONN CTR RT 36P MINI SAS G40H11332HR-W | R2_SA;HF_SA; | AMPHENOL | G40H11332HR-W |  |  | Purchase |  |  |  |  |
| 2 | B55.01102.0004 | 40.58D03.001 | LBL POLYIMIDE31.8*6.35 BARCODE | R2_SA;HF_SA;G_SA; | LABELJET | 40.58D03.001 | Single |  | Purchase | DIP | 2 | PCS |  |
| 2 | B55.01102.0004 | 40.6E727.001 | LBL 50X15MM BLANK WHITE POLYESTER | R2_SA;HF_SA; | WISTRON | 40.6E727.001 | Single |  | Purchase | DIP | 1 | PCS |  |
| 2 | B55.01102.0004 | 640.00X01.0001 | LBL 7X7MM  FOR SONIC | R2_SA;HF_SA; | WISTRON | 640.00X01.0001 | Single |  | Purchase | DIP | 1 | PCS |  |
| 2 | B55.01102.0004 | B34.0110T.0001 | HSINK 64X50X30_PUSHPIN_PAD SPONGE, CCI | R2_SA;HF_SA; | CCI | B34.0110T.0001 | Single |  | Purchase | DIP | 1 | PCS |  |
| 2 | B55.01102.0004 | B42.0111G.0021 | LATCH SCC R TEXTURE BRYCE CANYON MP | R2_SA;HF_SA; | FIVETECH | B42.0111G.0021 | Single |  | Purchase | DIP | 1 | PCS |  |
| 2 | B55.01102.0004 | B42.0111H.0021 | LATCH SCC L TEXTURE BRYCE CANYON MP | R2_SA;HF_SA; | FIVETECH | B42.0111H.0021 | Single |  | Purchase | DIP | 1 | PCS |  |
| 2 | B55.01102.0004 | B55.01102.M004 | BRYCE CANYON SCC W/O IOC GCE-1 P MAIN(S) | R2; |  |  |  | M | Manufacture | DIP | 1 | PCS |  |
| 3 | B55.01102.M004 | 064.41215.06DS | CHIP RES 4.12K F 1/16W 0402 | R2_SA;HF_SA;G_SA; | YAGEO;WALSIN;KOA | RC0402FR-074K12L;WR04X4121FTL;RK73H1ETQTP4121F | Multiple |  | Purchase | SMT | 1 | PCS | R15 |
| 3 | B55.01102.M004 | 064.51015.06DS | CHIP RES 5.1K F 1/16W 0402 | R2_SA;HF_SA;G_SA; | YAGEO;WALSIN;KOA | RC0402FR-075K1L;WR04X5101FTL;RK73H1ETQTP5101F | Multiple |  | Purchase | SMT | 1 | PCS | R16 |
| 3 | B55.01102.M004 | 064.R0035.0701 | CHIP RES 0.003 F 1W 0612 TCR+- 150PPM | R2_SA;HF_SA; | CYNTEC;VISHAY | RL1632L4-R003-FNH;WSK06123L000FEA | Multiple |  | Purchase | SMT | 1 | PCS | R14 |
| 3 | B55.01102.M004 | 068.1812N.1021 | CHIP IND 180NH K FP1007R6-R18-R | R2_SA;HF_SA; | COOPER | FP1007R6-R18-R | Multiple |  | Purchase | SMT | 1 | PCS | L31 |
| A | B55.01102.M004 | 068.1812N.1081 | CHIP IND 180NH K HCB1070C-181 | R2_SA;HF_SA; | DELTA | HCB1070C-181 |  |  | Purchase |  |  |  |  |
| 3 | B55.01102.M004 | 071.09306.0A0I | IC SMBUS/I2C PCA9306DCTR SSOP8 | R2_SA;HF_SA; | TI | PCA9306DCTR | Multiple |  | Purchase | SMT | 6 | PCS | U36 U37 U38 U39 U40 U41 |
| A | B55.01102.M004 | 073.09306.000B | IC TRANSLATOR PCA9306DP TSSOP 8P | R2_SA;HF_SA; | NXP | PCA9306DP |  |  | Purchase |  |  |  |  |
| 3 | B55.01102.M004 | 073.03166.000B | IC ANALOG SWITCH NX3L1G66GW,125 TSSOP5 | R2_SA;HF_SA; | NXP | NX3L1G66GW,125 | Single |  | Purchase | SMT | 2 | PCS | U119 U120 |
| 3 | B55.01102.M004 | 074.01278.0A7Z | IC SWAP CTRL ADM1278-2ACPZ-RL LFCSP 32P | R2_SA;HF_SA; | ADI | ADM1278-2ACPZ-RL | Single |  | Purchase | SMT | 1 | PCS | U5 |
| 3 | B55.01102.M004 | 074.03808.M001 | IC RESET TPS3808G01DBVR SOT-23 6P(LILY) | R2_SA;HF_SA; | TI | TPS3808G01DBVR | Single |  | Purchase | SMT | 1 | PCS | U23 |
| 3 | B55.01102.M004 | 075.87350.0071 | IC FET MOS CSD87350Q5D SON 8P | R2_SA;HF_SA; | TI | CSD87350Q5D | Single |  | Purchase | SMT | 1 | PCS | Q7 |
| 3 | B55.01102.M004 | 077.51571.0001 | CHIP CAP EL POLY 150U 6.3V M7343 ESR17 | R2_SA;HF_SA; | PANASONIC | EEJRX0J151R | Multiple |  | Purchase | SMT | 2 | PCS | TC4 TC5 |
| A | B55.01102.M004 | 077.C1571.0011 | CHIP CAP POLY T 150U 6.3V M7343 ESR18 | R2_SA;HF_SA; | NECTOKIN | PSKV0J157M018C |  |  | Purchase |  |  |  |  |
| A | B55.01102.M004 | 77.C1571.16L | CHIP CAP POLY T 150U 6.3V M7343 | R2_SA;HF_SA; | PANASONIC | EEFSX0J151ER |  |  | Purchase |  |  |  |  |
| 3 | B55.01102.M004 | 078.10321.02S1 | CHIP CAP C 0.01U 16V K0201 X7R | R2_SA;HF_SA;G_SA; | DARFON;MURATA;TAIYO;WALSIN;YAGEO;SAMSUNG | C0603X7R103KET;GRM033R71C103KE14D;EMK063B7103KP-F;0201B103K160CT;CC0201KRX7R7BB103;CL03B103KO3NNNC | Multiple |  | Purchase | SMT | 88 | PCS | C1 C10 C11 C12 C13 C14 C15 C16 C17 C18 C19 C2 C20 C21 C22 C23 C24 C25 C26 C27 C28 C29 C3 C30 C31 C32 C4 C49 C5 C50 C51 C52 C53 C54 C55 C56 C57 C58 C59 C6 C60 C61 C610 C62 C63 C64 C65 C66 C67 C677 C678 C679 C68 C680 C681 C682 C683 C69 C7 C70 C71 C72 C73 C74 C75 C76 C77 C78 C79 C8 C80 C81 C82 C83 C84 C85 C86 C87 C88 C89 C9 C90 C91 C92 C93 C94 C95 C96 |
| 3 | B55.01102.M004 | 078.10521.08F1 | CHIP CAP C 1UF 16V K 0402 X6S | R2_SA;HF_SA;G_SA; | MURATA;DARFON;YAGEO;TAIYO | GRM155C81C105KE11D;C1005X6S105KET;CC0402KRX6S7BB105;LMK105C6105KV-F | Multiple |  | Purchase | SMT | 2 | PCS | C214 C518 |
| 3 | B55.01102.M004 | 078.10621.0211 | CHIP CAP C 10UF 16V K0805 X7R | R2_SA;HF_SA;G_SA; | SAMSUNG;YAGEO | CL21B106KOQNNNE;CC0805KKX7R7BB106 | Multiple |  | Purchase | SMT | 16 | PCS | C527 C564 C565 C595 C666 C667 C668 C669 C670 C671 C698 C699 C700 C701 C702 C709 |
| 3 | B55.01102.M004 | 078.22610.08B1 | CHIP CAP C 22U 6.3V M0603 X6S MP | R2_SA;HF_SA; | MURATA;DARFON;WALSIN;YAGEO | GRM188C80J226ME15D;C1608X6S226MCT;0603S226M6R3CT;CC0603MRX6S5BB226 | Multiple |  | Purchase | SMT | 18 | PCS | C192 C196 C200 C204 C208 C228 C235 C242 C249 C256 C263 C275 C288 C295 C296 C303 C310 C719 |
| 3 | B55.01102.M004 | 078.47522.0211 | CHIP CAP C 4.7U 25V K0805 X7R | R2_SA;HF_SA;G_SA; | DARFON;MURATA;SAMSUNG;TAIYO;WALSIN;YAGEO | C2012X7R475KFP;GRM21BR71E475KA73L;CL21B475KAFNNNE;TMK212AB7475KG-T;0805B475K250CT;CC0805KKX7R8BB475 | Multiple |  | Purchase | SMT | 5 | PCS | C347 C511 C607 C616 C639 |
| 3 | B55.01102.M004 | 082.30005.0311 | XTAL 25MHZ 12P30PPM HSX211S SMD HARMONY | R2_SA;HF_SA; | HARMONY | X2C025000FC1H-HX | Multiple |  | Purchase | SMT | 1 | PCS | X1 |
| A | B55.01102.M004 | 82.30020.I61 | XTAL 25MHZ 20PPM 12PF HCX-1AB SMD | R2_SA;HF_SA; | HOSONIC | E1AB25.0000F12D22 |  |  | Purchase |  |  |  |  |
| 3 | B55.01102.M004 | 084.00925.003N | FET MOS PH0925CL,115 NC LFPAK 4P | R2_SA;HF_SA; | NXP | PH0925CL,115 | Single |  | Purchase | SMT | 1 | PCS | Q23 |
| 3 | B55.01102.M004 | 084.3K324.0031 | FET MOS NC SSM3K324R SOT-23F 3P | R2_SA;HF_SA; | TOSHIBA | SSM3K324R | Multiple |  | Purchase | SMT | 1 | PCS | Q2 |
| A | B55.01102.M004 | 084.06244.0031 | FET MOS IRLML6244TRPBF SOT-23 | R2_SA;HF_SA; | IR | IRLML6244TRPBF |  |  | Purchase |  |  |  |  |
| 3 | B55.01102.M004 | 63.00000.00L | CHIP RES 0 J 1/10W 0603 | R2_SA;HF_SA;G_SA; | TA-I ; RALEC ; YAGEO ; WALSIN | RM06JTN0 ; RTT03000JTP ; RC0603JR-070RL ; WR06X000PTL | Multiple |  | Purchase | SMT | 3 | PCS | R480 R481 R482 |
| 3 | B55.01102.M004 | 63.10034.1DL | CHIP RES 10 J 1/16W 0402 | R2_SA;HF_SA;G_SA; | TA-I ; RALEC ; CYNTEC ; YAGEO;WALSIN | RM04JTN100 ; RTT02100JTH ; RR0510S-100-JN ; RC0402JR-0710RL;WR04X100JTL | Multiple |  | Purchase | SMT | 1 | PCS | R474 |
| 3 | B55.01102.M004 | 63.10234.1DL | CHIP RES 1K J 1/16W 0402 | R2_SA;HF_SA;G_SA; | TA-I;RALEC;CYNTEC;YAGEO;WALSIN | RM04JTN102 ; RTT02102JTH ; RR0510S-102-JN ; RC0402JR-071KL;WR04X102JTL | Multiple |  | Purchase | SMT | 2 | PCS | R531 R607 |
| 3 | B55.01102.M004 | 63.10434.L1L | CHIP RES 100K J 1/16W 0402 13" REEL | R2_SA;HF_SA;G_SA; | YAGEO;RALEC;WALSIN;TAI | RC0402JR-13100KL;RTT02104JH5;WR04X104 JHL;RM04JLN104 | Multiple |  | Purchase | SMT | 3 | PCS | R17 R18 R19 |
| 3 | B55.01102.M004 | 63.2R233.15L | CHIP RES 2.2 J 1/10W 0603 | R2_SA;HF_SA;G_SA; | TA-I ; RALEC ; YAGEO ; WALSIN | RM06JTN2R2 ; RTT032R2JTP ; RC0603JR-072R2L ; WR06X2R2JTL | Multiple |  | Purchase | SMT | 2 | PCS | R28 R499 |
| 3 | B55.01102.M004 | 63.62334.1DL | CHIP RES 62K J 1/16W 0402 | R2_SA;HF_SA;G_SA; | TA-I ; RALEC ; CYNTEC ; YAGEO | RM04JTN623 ; RTT02623JTH ; RR0510S-623-JN ; RC0402JR-0762KL | Multiple |  | Purchase | SMT | 1 | PCS | R401 |
| 3 | B55.01102.M004 | 63.75334.1DL | CHIP RES 75K J 1/16W 0402 | R2_SA;HF_SA;G_SA; | TA-I ;  RALEC ; CYNTEC;YAGEO | RM04JTN753 ; RTT02753JTH ; RR-0510S-753-JN ; RC0402JR-0775KL | Multiple |  | Purchase | SMT | 1 | PCS | R609 |
| 3 | B55.01102.M004 | 63.82234.1DL | CHIP RES 8.2K J 1/16W 0402 | R2_SA;HF_SA;G_SA; | TA-I;RALEC;CYNTEC;YAGEO;WALSIN | RM04JTN822 ; RTT02822JTH ; RR0510S-822-JN ; RC0402JR-078K2L;WR04X822JTL | Multiple |  | Purchase | SMT | 1 | PCS | R356 |
| 3 | B55.01102.M004 | 63.R0031.16L | CHIP RES 0 J 1/8W 0805 | R2_SA;HF_SA;G_SA; | TAI;RALEC;YAGEO;WALSIN | RM10JTN0 ; RTT05000JTP ; RC0805JR-070RL ; WR08X000PTL | Multiple |  | Purchase | SMT | 8 | PCS | R24 R26 R382 R509 R510 R511 R527 R84 |
| 3 | B55.01102.M004 | 63.R0034.1DL | CHIP RES 0 J 1/16W 0402 | R2_SA;HF_SA;G_SA; | TAI;RALEC;CYNTEC;YAGEO;WALSIN | RM04JTN0;RTT02000JTH;RR0510X-000-XN;RC0402JR-070RL;WR04X000PTL | Multiple |  | Purchase | SMT | 67 | PCS | R100 R101 R102 R103 R105 R12 R121 R13 R132 R133 R156 R206 R207 R210 R211 R245 R25 R289 R290 R292 R293 R294 R295 R314 R315 R326 R327 R341 R347 R348 R351 R354 R355 R372 R383 R386 R387 R406 R415 R423 R424 R433 R434 R461 R473 R517 R525 R536 R540 R542 R545 R558 R572 R574 R576 R578 R579 R582 R585 R692 R75 R76 R80 R88 R90 R92 R95 |
| 3 | B55.01102.M004 | 64.10006.6DL | CHIP RES 100 D 1/16W 0402 | R2_SA;HF_SA;G_SA; | RALEC;TAI;CYNTEC;YAGEO | RTT021000DTH;RM04DTN1000;RR0510P-101-DN;RC0402DR-07100RL | Multiple |  | Purchase | SMT | 2 | PCS | R435 R436 |
| 3 | B55.01102.M004 | 64.10015.6DL | CHIP RES 1K F 1/16W 0402 | R2_SA;HF_SA;G_SA; | TA-I;RALEC;CYNTEC;YAGEO;WALSIN | RM04FTN1001 ; RTT021001FTH ; RR0510S-102-FN ; RC0402FR-071KL;WR04X1001FTL | Multiple |  | Purchase | SMT | 16 | PCS | R321 R322 R323 R380 R400 R413 R414 R445 R62 R63 R66 R67 R68 R69 R70 R71 |
| 3 | B55.01102.M004 | 64.10025.6DL | CHIP RES 10K F 1/16W 0402 | R2_SA;HF_SA;G_SA; | TA-I;RALEC;CYNTEC;YAGEO;WALSIN | RM04FTN1002 ; RTT021002FTH ; RR0510S-103-FN ; RC0402FR-0710KL;WR04X1002FTL | Multiple |  | Purchase | SMT | 26 | PCS | R120 R129 R139 R149 R246 R27 R286 R291 R307 R308 R309 R312 R373 R375 R398 R403 R404 R487 R500 R518 R528 R555 R557 R608 R693 R97 |
| 3 | B55.01102.M004 | 64.10035.6DL | CHIP RES 100K F 1/16W 0402 | R2_SA;HF_SA;G_SA; | TA-I;RALEC;CYNTEC;YAGEO;WALSIN | RM04FTN1003 ; RTT021003FTH ; RR0510S-104-FN ; RC0402FR-07100KL;WR04X1003FTL | Multiple |  | Purchase | SMT | 1 | PCS | R532 |
| 3 | B55.01102.M004 | 64.10R05.16L | CHIP RES 10 F 1/8W 0805(ROHS) | R2_SA;HF_SA;G_SA; | TAI;YAGEO;RALEC | RM10FTN10R0;RC0805FR-0710RL;RTT0510R0FTP | Multiple |  | Purchase | SMT | 1 | PCS | R526 |
| 3 | B55.01102.M004 | 64.10R05.55L | CHIP RES 10 F 1/10W 0603 | R2_SA;HF_SA;G_SA; | TA-I;RALEC;YAGEO;WALSIN | RM06FTN10R0 ; RTT0310R0FTP ; RC0603FR-0710RL;WR06X10R0FTL | Multiple |  | Purchase | SMT | 2 | PCS | R29 R512 |
| 3 | B55.01102.M004 | 64.10R05.6DL | CHIP RES 10 F 1/16W 0402 | R2_SA;HF_SA;G_SA; | TAI;RALEC;CYNTEC;YAGEO;WALSIN | RM04FTN10R0;RTT0210R0FTH;RR0510S-100-FN;RC0402FR-0710RL;WR04X10R0FTL | Multiple |  | Purchase | SMT | 10 | PCS | R11 R151 R152 R153 R154 R155 R519 R520 R522 R523 |
| 3 | B55.01102.M004 | 64.11025.6DL | CHIP RES 11K F 1/16W 0402 | R2_SA;HF_SA;G_SA; | TA-I ; RALEC ; CYNTEC ; YAGEO;WALSIN | RM04FTN1102 ; RTT021102FTH ; RR0510S-1102-FN ; RC0402FR-0711KL;WR04X1102FTL | Multiple |  | Purchase | SMT | 1 | PCS | R543 |
| 3 | B55.01102.M004 | 64.15005.6DL | CHIP RES 150 F 1/16W 0402 | R2_SA;HF_SA;G_SA; | TAI;RALEC;CYNTEC;YAGEO;WALSIN | RM04FTN1500 ; RTT021500FTH ; RR0510S-1500-FN ; RC0402FR-07150RL;WR04X1500FTL | Multiple |  | Purchase | SMT | 1 | PCS | R94 |
| 3 | B55.01102.M004 | 64.15015.6DL | CHIP RES 1.5K F 1/16W 0402 | R2_SA;HF_SA;G_SA; | TA-I;RALEC;CYNTEC;YAGEO;WALSIN | RM04FTN1501 ; RTT021501FTH ; RR0510S-152-FN ; RC0402FR-071K5L;WR04X1501FTL | Multiple |  | Purchase | SMT | 1 | PCS | R378 |
| 3 | B55.01102.M004 | 64.15025.6DL | CHIP RES 15K F 1/16W 0402 | R2_SA;HF_SA;G_SA; | TA-I;RALEC;CYNTEC;YAGEO | RM04FTN1502;RTT021502FTH;RR0510S-153-FN;RC0402FR-0715KL | Multiple |  | Purchase | SMT | 1 | PCS | R377 |
| 3 | B55.01102.M004 | 64.19625.6DL | CHIP RES 19.6K F 1/16W 0402 | R2_SA;HF_SA;G_SA; | RALEC ; CYNTEC ; TA-I ; YAGEO | RTT021962FTH ; RR0510S-1962-FN ; RM04FTN1962 ; RC0402FR-0719K6L | Multiple |  | Purchase | SMT | 1 | PCS | R501 |
| 3 | B55.01102.M004 | 64.1R005.16L | CHIP RES 1 F 1/8W 0805 | R2_SA;HF_SA;G_SA; | TAI;YAGEO;RALEC;WALSIN | RM10FTN1R00;RC0805FR-071RL;RTT051R00FTP;WR08W1R00FTL | Multiple |  | Purchase | SMT | 1 | PCS | R479 |
| 3 | B55.01102.M004 | 64.20035.6DL | CHIP RES 200K F 1/16W 0402 | R2_SA;HF_SA;G_SA; | TA-I;RALEC;CYNTEC;YAGEO;WALSIN | RM04FTN2003 ; RTT022003FTH ; RR0510S-204-FN ; RC0402FR-07200KL;WR04X2003FTL | Multiple |  | Purchase | SMT | 6 | PCS | R425 R426 R437 R438 R439 R441 |
| 3 | B55.01102.M004 | 64.22635.6DL | CHIP RES 226K F 1/16W 0402 | R2_SA;HF_SA;G_SA; | TA-I ; RALEC ; CYNTEC ; YAGEO | RM04FTN2263 ; RTT022263FTH ; RR0510S-2263-FN ; RC0402FR-07226KL | Multiple |  | Purchase | SMT | 1 | PCS | R22 |
| 3 | B55.01102.M004 | 64.27015.6DL | CHIP RES 2.7K F 1/16W 0402 | R2_SA;HF_SA;G_SA; | TAI;RALEC;CYNTEC;YAGEO | RM04FTN2701;RTT022701FTH;RR0510S-2701-FN;RC0402FR-072K7L | Multiple |  | Purchase | SMT | 1 | PCS | R514 |
| 3 | B55.01102.M004 | 64.28715.6DL | CHIP RES 2.87K F 1/16W 0402 | R2_SA;HF_SA;G_SA; | TA-I;RALEC;CYNTEC;YAGEO | RM04FTN2871;RTT022871FTH;RR0510S-2871-FN;RC0402FR-072K87L | Multiple |  | Purchase | SMT | 1 | PCS | R98 |
| 3 | B55.01102.M004 | 64.2R205.55L | CHIP RES 2.2 F 1/10W 0603 | R2_SA;HF_SA;G_SA; | TAI;YAGEO;RALEC;WALSIN | RM06FTN2R20;RC0603FR-072R2L;RTT032R20FTP;WR06W2R20FTL | Multiple |  | Purchase | SMT | 3 | PCS | R381 R440 R515 |
| 3 | B55.01102.M004 | 64.30115.6DL | CHIP RES 3.01K F 1/16W 0402 | R2_SA;HF_SA;G_SA; | TA-I;RALEC;CYNTEC;YAGEO;WALSIN | RM04FTN3011 ; RTT023011FTH ; RR0510S-3011-FN ; RC0402FR-073K01L;WR04X3011FTL | Multiple |  | Purchase | SMT | 1 | PCS | R115 |
| 3 | B55.01102.M004 | 64.34025.6DL | CHIP RES 34K F 1/16W 0402 | R2_SA;HF_SA;G_SA; | TA-I ; RALEC ; CYNTEC ; YAGEO | RM04FTN3402 ; RTT023402FTH ; RR0510S-3402-FN ; RC0402FR-0734KL | Multiple |  | Purchase | SMT | 1 | PCS | R140 |
| 3 | B55.01102.M004 | 64.35715.6DL | CHIP RES 3.57K F 1/16W 0402 | R2_SA;HF_SA;G_SA; | TA-I;RALEC;CYNTEC;YAGEO | RM04FTN3571;RTT023571FTH;RR0510S-3571-FN;RC0402FR-073K57L | Multiple |  | Purchase | SMT | 1 | PCS | R99 |
| 3 | B55.01102.M004 | 64.38325.6DL | CHIP RES 38.3K F 1/16W 0402 | R2_SA;HF_SA;G_SA; | TAI;RALEC;CYNTEC;YAGEO | RM04FTN3832;RTT023832FTH;RR0510S-3832-FN;RC0402FR-0738K3L | Multiple |  | Purchase | SMT | 1 | PCS | R521 |
| 3 | B55.01102.M004 | 64.44225.6DL | CHIP RES 44.2K F 1/16W 0402 | R2_SA;HF_SA;G_SA; | TAI;RALEC;CYNTEC;YAGEO;WALSIN | RM04FTN4422;RTT024422FTH;RR0510S-4422-FN;RC0402FR-0744K2L;WR04X4422FTL | Multiple |  | Purchase | SMT | 1 | PCS | R513 |
| 3 | B55.01102.M004 | 64.45325.6DL | CHIP RES 45.3K F 1/16W 0402 | R2_SA;HF_SA;G_SA; | TA-I ; RALEC ; CYNTEC ; YAGEO;WALSIN | RM04FTN4532 ; RTT024532FTH ; RR0510S-4532-FN ; RC0402FR-0745K3L;WR04X4532FTL | Multiple |  | Purchase | SMT | 1 | PCS | R548 |
| 3 | B55.01102.M004 | 64.47015.6DL | CHIP RES 4.7K F 1/16W 0402 | R2_SA;HF_SA;G_SA; | TA-I;RALEC;CYNTEC;YAGEO;WALSIN | RM04FTN4701;RTT024701FTH;RR0510S-472-FN;RC0402FR-074K7L;WR04X4701FTL | Multiple |  | Purchase | SMT | 49 | PCS | R126 R127 R128 R130 R131 R135 R141 R142 R143 R144 R145 R146 R147 R333 R335 R345 R346 R36 R360 R362 R363 R37 R39 R397 R40 R41 R42 R43 R44 R46 R48 R49 R50 R51 R52 R53 R54 R55 R56 R57 R58 R59 R60 R61 R64 R65 R72 R77 R78 |
| 3 | B55.01102.M004 | 64.47515.6DL | CHIP RES 4.75K F 1/16W 0402 | R2_SA;HF_SA;G_SA; | TA-I;RALEC;CYNTEC;YAGEO | RM04FTN4751;RTT024751FTH;RR0510S-4751-FN;RC0402FR-074K75L | Multiple |  | Purchase | SMT | 28 | PCS | R106 R107 R108 R109 R110 R111 R112 R113 R114 R116 R117 R119 R122 R123 R136 R137 R138 R150 R212 R236 R301 R302 R34 R35 R350 R47 R85 R86 |
| 3 | B55.01102.M004 | 64.47535.6DL | CHIP RES 475K F 1/16W 0402 | R2_SA;HF_SA;G_SA; | TA-I;RALEC;CYNTEC;YAGEO | RM04FTN4753;RTT024753FTH;RR0510S-4753-FN;RC0402FR-07475KL | Multiple |  | Purchase | SMT | 2 | PCS | R31 R508 |
| 3 | B55.01102.M004 | 64.49925.6DL | CHIP RES 49.9K F 1/16W 0402 | R2_SA;HF_SA;G_SA; | TA-I ; RALEC ; CYNTEC ; YAGEO ; WALSIN | RM04FTN4992 ; RTT024992FTH ; RR0510S-4992-FN ; RC0402FR-0749K9L ; WR04X4992FTL | Multiple |  | Purchase | SMT | 2 | PCS | R550 R551 |
| 3 | B55.01102.M004 | 64.51025.6DL | CHIP RES 51K F 1/16W 0402 | R2_SA;HF_SA;G_SA; | TA-I ; RALEC ; CYNTEC ; YAGEO;WALSIN | RM04FTN5102 ; RTT025102FTH ; RR0510S-513-FN ; RC0402FR-0751KL;WR04X5102FTL | Multiple |  | Purchase | SMT | 1 | PCS | R504 |
| 3 | B55.01102.M004 | 64.6342D.6DL | CHIP RES 63.4K B 1/16W 0402 | R2_SA;HF_SA;G_SA; | TAI ; RALEC ; CYNTEC ; YAGEO | RB04BTS6342 ; RTX026342BETH ; RR0510Q-6342-BN ; RT0402BRE0763K4L | Multiple |  | Purchase | SMT | 1 | PCS | R20 |
| 3 | B55.01102.M004 | 64.69825.6DL | CHIP RES 69.8K F 1/16W 0402 | R2_SA;HF_SA;G_SA; | TA-I;RALEC;CYNTEC;YAGEO | RM04FTN6982;RTT026982FTH;RR0510S-6982-FN;RC0402FR-0769K8L | Multiple |  | Purchase | SMT | 1 | PCS | R320 |
| 3 | B55.01102.M004 | 64.80615.6DL | CHIP RES 8.06K F 1/16W 0402 | R2_SA;HF_SA;G_SA; | TA-I;RALEC;CYNTEC;YAGEO;WALSIN | RM04FTN8061;RTT028061FTH;RR0510S-8061-FN;RC0402FR-078K06L;WR04X8061FTL | Multiple |  | Purchase | SMT | 1 | PCS | R399 |
| 3 | B55.01102.M004 | 64.R0005.6DL | CHIP RES 0 F 1/16W 0402 | R2_SA;HF_SA;G_SA; | RALEC;CYNTEC;TAI;YAGEO;WALSIN | RTT020000FTH;RR0510S-000-FNH;RM04FTN0;RC0402FR-070RL;WR04X000 PTL | Multiple |  | Purchase | SMT | 2 | PCS | R477 R478 |
| 3 | B55.01102.M004 | 64.R5105.55L | CHIP RES 0.51 F 1/10W 0603 L/F | R2_SA;HF_SA;G_SA; | RALEC ; TA-I ; YAGEO ; WALSIN | RTT03R510FTP ; RL06FTNR510 ; RL0603FR-070R51L ; WW06XR510FTL | Multiple |  | Purchase | SMT | 13 | PCS | R134 R157 R158 R159 R160 R161 R162 R163 R164 R165 R166 R167 R168 |
| 3 | B55.01102.M004 | 68.00084.771 | CHIP BEAD BLM41PG600SN1L MURAT | R2_SA;HF_SA; | MURATA | BLM41PG600SN1L | Multiple |  | Purchase | SMT | 1 | PCS | L30 |
| A | B55.01102.M004 | 68.00214.071 | CHIP BEAD HCB4516KF-600T60(LF) | R2_SA;HF_SA; | TAITECH | HCB4516KF-600T60 |  |  | Purchase |  |  |  |  |
| A | B55.01102.M004 | 68.00376.031 | CHIP BEAD BCMS451616A600 | R2_SA;HF_SA; | MAXECHO | BCMS451616A600 |  |  | Purchase |  |  |  |  |
| 3 | B55.01102.M004 | 68.00084.831 | CHIP BEAD BLM21PG220SN1D (LF) | R2_SA;HF_SA; | MURATA | BLM21PG220SN1D | Multiple |  | Purchase | SMT | 2 | PCS | L28 L6 |
| A | B55.01102.M004 | 68.00216.081 | CHIP BEAD HCB2012KF-220T60 | R2_SA;HF_SA; | TAITECH | HCB2012KF-220T60 |  |  | Purchase |  |  |  |  |
| 3 | B55.01102.M004 | 68.00224.051 | CHIP BEAD MPZ2012S300AT TDK | R2_SA;HF_SA; | TDK | MPZ2012S300AT | Multiple |  | Purchase | SMT | 13 | PCS | L10 L11 L12 L13 L14 L15 L16 L17 L18 L35 L7 L8 L9 |
| A | B55.01102.M004 | 068.00002.0091 | CHIP BEAD BLM21SN300SN1D MURATA | R2_SA;HF_SA; | MURATA | BLM21SN300SN1D |  |  | Purchase |  |  |  |  |
| 3 | B55.01102.M004 | 68.00224.201 | CHIP BEAD MPZ2012S601AT TDK | R2_SA;HF_SA; | TDK | MPZ2012S601AT | Single |  | Purchase | SMT | 5 | PCS | L1 L2 L3 L4 L5 |
| 3 | B55.01102.M004 | 68.2R21A.20B | CHIP CHOKE 2.2U PCMB063T-2R2MS | R2_SA;HF_SA; | CYNTEC | PCMB063T-2R2MS | Multiple |  | Purchase | SMT | 1 | PCS | L29 |
| A | B55.01102.M004 | 68.2R210.20P | CHIP CHOKE 2.2UH MPLCG0630L2R2 | R2_SA;HF_SA; | NEC;TOKIN | MPLCG0630L2R2 |  |  | Purchase |  |  |  |  |
| A | B55.01102.M004 | 68.2R21E.10X | CHIP IND 2.2UH M SPM6530T-2R2M | R2_SA;HF_SA; | TDK | SPM6530T-2R2M |  |  | Purchase |  |  |  |  |
| 3 | B55.01102.M004 | 68.3R310.20V | CHIP CHOKE 3.3UH PCMB063T-3R3MS | R2_SA;HF_SA; | CYNTEC | PCMB063T-3R3MS | Multiple |  | Purchase | SMT | 1 | PCS | L34 |
| A | B55.01102.M004 | 68.3R31A.10V | CHIP IND 3.3UH MMD-06CZ-3R3M-V | R2_SA;HF_SA;G_SA; | MAGLAYER | MMD-06CZ-3R3M-V1W |  |  | Purchase |  |  |  |  |
| A | B55.01102.M004 | 68.3R31A.20D | CHIP CHOKE 3.3UH M PCMB065T-3R3MS | R2_SA;HF_SA; | CYNTEC | PCMB065T-3R3MS |  |  | Purchase |  |  |  |  |
| 3 | B55.01102.M004 | 71.03X48.00U | IC SAS EXPANDER SAS3X48 FPB22GU 1020P | R2_SA;HF_SA; | LSI | SAS3X48C1-DB(500021061) | Single |  | Purchase | SMT | 1 | PCS | U1 |
| 3 | B55.01102.M004 | 72.24C64.I01 | IC EEPROM CAT24C64WI-GT3 SOIC 8P | R2_SA;HF_SA;G_SA; | ON | CAT24C64WI-GT3 | Multiple |  | Purchase | SMT | 1 | PCS | U27 |
| A | B55.01102.M004 | 72.24C64.K01 | IC EEPROM M24C64-RMN6TP SOIC 8P | R2_SA;HF_SA; | STMICROELECTRONICS INC | M24C64-RMN6TP |  |  | Purchase |  |  |  |  |
| 3 | B55.01102.M004 | 72.24C64.K01 | IC EEPROM M24C64-RMN6TP SOIC 8P | R2_SA;HF_SA; | STMICROELECTRONICS INC | M24C64-RMN6TP | Multiple |  | Purchase | SMT | 1 | PCS | U29 |
| A | B55.01102.M004 | 072.02464.0A01 | IC EEPROM FM24C64D-SO-T-G SOP 8P | R2_SA;HF_SA; | FUDAN | FM24C64D-SO-T-G |  |  | Purchase |  |  |  |  |
| 3 | B55.01102.M004 | 73.00102.007 | IC TRANSLATOR TXS0102DCUR VSSOP 8P | R2_SA;HF_SA; | TI | TXS0102DCUR | Multiple |  | Purchase | SMT | 2 | PCS | U20 U21 |
| A | B55.01102.M004 | 71.09406.001 | IC I2C/SMBUS TCA9406DCUR US8 | R2_SA;HF_SA; | TI | TCA9406DCUR |  |  | Purchase |  |  |  |  |
| 3 | B55.01102.M004 | 73.01G11.AHH | IC CMOS SN74LVC1G11DCKR DCK | R2_SA;HF_SA;G_SA; | TI | SN74LVC1G11DCKR | Multiple |  | Purchase | SMT | 1 | PCS | U42 |
| A | B55.01102.M004 | 073.74111.000J | IC CMOS GATE U74LVC1G11G-AL6-R SOT363 6P | R2_SA;HF_SA; | UTC | U74LVC1G11G-AL6-R |  |  | Purchase |  |  |  |  |
| 3 | B55.01102.M004 | 73.1G126.DHG | IC CMOS SN74LVC1G126DCKR SC70 | R2_SA;HF_SA; | TI | SN74LVC1G126DCKR | Multiple |  | Purchase | SMT | 1 | PCS | U48 |
| A | B55.01102.M004 | 073.7S126.000G | IC CMOS TC7SZ126FU,LJ(CT SSOP5-P-0.65A | R2_SA;HF_SA; | TOSHIBA | TC7SZ126FU,LJ(CT |  |  | Purchase |  |  |  |  |
| A | B55.01102.M004 | 73.7S126.AAH | IC CMOS NC7SZ126P5X SC70-5 | R2_SA;HF_SA; | FAIRCHILD | NC7SZ126P5X |  |  | Purchase |  |  |  |  |
| 3 | B55.01102.M004 | 73.8T245.B29 | IC XCVR SN74LVC8T245DGVR TVSOP | R2_SA;HF_SA; | TI | SN74LVC8T245DGVR | Single |  | Purchase | SMT | 3 | PCS | U12 U14 U24 |
| 3 | B55.01102.M004 | 74.01015.049 | IC CONV ADS1015IDGSR MSOP 10P | R2_SA;HF_SA; | TI | ADS1015IDGSR | Single |  | Purchase | SMT | 1 | PCS | U25 |
| 3 | B55.01102.M004 | 74.51219.A73 | IC BUCK CTRL TPS51219RTER(MP) QFN 16P | R2_SA;HF_SA; | TI | TPS51219RTER | Single |  | Purchase | SMT | 1 | PCS | U8 |
| 3 | B55.01102.M004 | 74.53318.073 | IC PWR CTRL TPS53318DQPR QFN 22P | R2_SA;HF_SA; | TI | TPS53318DQPR | Single |  | Purchase | SMT | 2 | PCS | U10 U11 |
| 3 | B55.01102.M004 | 74.74801.A33 | IC LDO TPS74801RGW QFN 20P | R2_SA;HF_SA; | TI | TPS74801RGW | Single |  | Purchase | SMT | 1 | PCS | U4 |
| 3 | B55.01102.M004 | 74.78M05.03C | IC A.R UA78M05CDCYRG3 SOT-223 | R2_SA;HF_SA; | TI | UA78M05CDCYRG3 | Single |  | Purchase | SMT | 1 | PCS | U7 |
| 3 | B55.01102.M004 | 78.10222.20L | CHIP CAP C 1000P 25V K0201 X7R | R2_SA;HF_SA;G_SA; | MURATA;TDK;PHYCOMP;DARFON;WALSIN | GRM033R71E102KA01D;C0603X7R1E102KT00NN;223891815623;C0603X7R102KFT;0201B102K250CT | Multiple |  | Purchase | SMT | 9 | PCS | C123 C124 C125 C126 C127 C187 C188 C189 C190 |
| 3 | B55.01102.M004 | 78.10224.2FL | CHIP CAP C 1000P 50V K0402 X7R | R2_SA;R_SA;HF_SA;G_SA; | AVX;DARFON;MURATA;PHYCOMP;SAMSUNG;TAIYO;MURATA;AVX;YAGEO | CM05X7R102K50AH;C1005X7R102KGT;GRM155R71H102KA01D;223858715623;CL05B102KB5NNNC;UMK105B7102KV-F;WBM155R71H102KA01D;04025C102KAT2A;CC0402KRX7R9BB102 | Multiple |  | Purchase | SMT | 5 | PCS | C611 C615 C618 C640 C655 |
| 3 | B55.01102.M004 | 78.10322.2FL | CHIP CAP C 0.01U 25V K0402 X7R | R2_SA;HF_SA;G_SA; | AVX;DARFON;MURATA;PHYCOMP;SAMSUNG;TAIYO;TDK;MURATA;YAGEO | 04023C103KAT2A;C1005X7R103KFT;GRM155R71E103KA01D;223891715636;CL05B103KA5NNNC;TMK105BJ103KV-F;C1005X7R1E103KT000F;WBM155R71E103KA01D;CC0402KRX7R8BB103 | Multiple |  | Purchase | SMT | 5 | PCS | C113 C529 C612 C613 C648 |
| 3 | B55.01102.M004 | 78.10420.50L | CHIP CAP C 0.1U 6.3V K0201 X5R | R2_SA;HF_SA;G_SA; | MURATA;AVX;DARFON;WALSIN;MATSUKI;TAIYO;SAMSUNG;SAMSUNG;YAGEO | GRM033R60J104KE19D;02016D104KAT2A;C0603X5R104KCT;0201X104K6R3CT;MAG01X5R0J104K;JMK063BJ104KP-F;CL03A104KQ3NNNH;CL03A104KQ3NNNHC;CC0201KRX5R5BB104 | Multiple |  | Purchase | SMT | 132 | PCS | C128 C129 C130 C131 C132 C133 C134 C135 C136 C137 C138 C139 C140 C141 C142 C143 C144 C145 C146 C147 C148 C149 C150 C151 C152 C153 C154 C155 C156 C157 C158 C159 C160 C161 C162 C163 C164 C165 C166 C167 C168 C169 C170 C171 C172 C173 C174 C175 C176 C177 C178 C179 C180 C181 C182 C195 C199 C203 C207 C211 C230 C231 C232 C233 C237 C238 C239 C240 C244 C245 C246 C247 C251 C252 C253 C254 C258 C259 C260 C261 C265 C266 C267 C268 C269 C271 C272 C273 C276 C278 C279 C280 C282 C284 C285 C286 C289 C291 C292 C293 C297 C299 C300 C301 C304 C306 C307 C308 C512 C513 C514 C531 C536 C537 C538 C539 C540 C578 C579 C580 C581 C582 C583 C584 C585 C586 C587 C588 C589 C590 C591 C592 |
| 3 | B55.01102.M004 | 78.10421.2FL | CHIP CAP C 0.1U 16V K0402 X7R | R2_SA;HF_SA;G_SA; | DARFON;MURATA;PHYCOMP;SAMSUNG;TAIYO;WALSIN;YAGEO | C1005X7R104KET;GRM155R71C104KA88D;223878715649;CL05B104KO5NNNC;EMK105B7104KV-F;0402B104K160CT;CC0402KRX7R7BB104 | Multiple |  | Purchase | SMT | 63 | PCS | C101 C104 C112 C114 C116 C117 C215 C216 C217 C218 C219 C220 C221 C222 C223 C224 C225 C226 C502 C503 C504 C505 C506 C507 C509 C515 C516 C517 C519 C523 C524 C525 C526 C528 C530 C545 C548 C549 C550 C551 C552 C557 C558 C559 C560 C561 C562 C575 C576 C594 C596 C600 C604 C641 C647 C674 C693 C705 C731 C732 C733 C97 C98 |
| 3 | B55.01102.M004 | 78.10424.2BL | CHIP CAP C 0.1U 50V K0603 X7R | R2_SA;HF_SA;G_SA; | MURATA;AVX;PHYCOMP;SAMSUNG;DARFON;WALSIN;YAGEO | GRM188R71H104KA93D;06035C104KAT2A;223858615649;CL10B104KB8NNNC;C1608X7R104KGT;0603B104K500CT;CC0603KRX7R9BB104 | Multiple |  | Purchase | SMT | 9 | PCS | C651 C652 C653 C656 C672 C673 C675 C697 C713 |
| 3 | B55.01102.M004 | 78.10510.5SL | CHIP CAP C 1U 6.3V M0201 X5R | R2_SA;HF_SA;G_SA; | MURATA;DARFON;TAIYO;SAMSUNG;AVX;WALSIN;YAGEO | GRM033R60J105MEA2D;C0603X5R105MCT;JDK063BJ105MP-FD;CL03A105MQ3CSNH;CV03X5R105M06AH;0201X105M6R3;CC0201MRX5R5BB105 | Multiple |  | Purchase | SMT | 17 | PCS | C194 C198 C202 C206 C210 C229 C236 C243 C250 C257 C264 C274 C281 C287 C294 C302 C309 |
| 3 | B55.01102.M004 | 78.10521.2BL | CHIP CAP C 1U 16V K0603 X7R | R2_SA;HF_SA;G_SA; | KEMET;MURATA;TAIYO;TDK;YAGEO;WALSIN;SAMSUNG;DARFON | C0603C105K4RAC;GRM188R71C105KA12D;EMK107B7105KA-T;C1608X7R1C105KT;CC0603KRX7R7BB105;0603B105K160CT;CL10B105KO8NNNC;C1608X7R105KET | Multiple |  | Purchase | SMT | 7 | PCS | C348 C603 C606 C638 C649 C650 C714 |
| 3 | B55.01102.M004 | 78.10522.2BL | CHIP CAP C 1U 25V K0603 X7R | R2_SA;HF_SA;G_SA; | MURATA;TAIYO;WALSIN;SAMSUNG;DARFON;YAGEO | GRM188R71E105KA12D;TMK107B7105KA-T;0603B105K250CT;CL10B105KA8NNNC;C1608X7R105KFT;CC0603KRX7R8BB105 | Multiple |  | Purchase | SMT | 1 | PCS | C646 |
| 3 | B55.01102.M004 | 78.10610.5FL | CHIP CAP C 10U 6.3V M0402 X5R | R2_SA;HF_SA;G_SA; | MURATA;YAGEO;SAMSUNG;TAIYO;DARFON;WALSIN | GRM155R60J106ME44D;CC0402MRX5R5BB106;CL05A106MQ5NUNC;JMK105CBJ106MV-F;C1005X5R106MCT;0402X106M6R3CT | Multiple |  | Purchase | SMT | 14 | PCS | C118 C119 C120 C121 C122 C183 C184 C185 C186 C193 C197 C201 C205 C209 |
| 3 | B55.01102.M004 | 78.10620.21L | CHIP CAP C 10U 6.3V K0805 X7R | R2_SA;HF_SA;G_SA; | MURATA;TAIYO;DARFON;KYOCERA | GRM21BR70J106KE76L;JMK212B7106KG-T;C2012X7R106KC;CM21X7R106K06AT | Multiple |  | Purchase | SMT | 15 | PCS | C109 C614 C617 C684 C685 C686 C687 C688 C694 C695 C703 C704 C706 C707 C708 |
| 3 | B55.01102.M004 | 78.10710.52L | CHIP CAP C 100U 6.3V M1206 X5R | R2_SA;HF_SA;G_SA; | MURATA;TAIYO;SAMSUNG;WALSIN | GRM31CR60J107ME39L;JMK316BJ107ML;CL31A107MQHNNNE;1206X107M6R3CT | Multiple |  | Purchase | SMT | 13 | PCS | C227 C234 C241 C248 C255 C262 C270 C277 C283 C290 C298 C305 C720 |
| 3 | B55.01102.M004 | 78.15034.1FL | CHIP CAP C 15P 50V J0402 NPO | R2_SA;HF_SA;G_SA; | AVX;DARFON;MURATA;PHYCOMP;SAMSUNG;TAIYO;WALSIN;YAGEO | 04025A150JAT2A;C1005NP0150JGT;GRM1555C1H150JA01D;223886915159;CL05C150JB5NNNC;UMK105CH150JV-F;0402N150J500CT;CC0402JRNPO9BN150 | Multiple |  | Purchase | SMT | 2 | PCS | C110 C111 |
| 3 | B55.01102.M004 | 78.15322.2FL | CHIP CAP C 0.015U 25V K0402 X7R | R2_SA;HF_SA;G_SA; | MURATA;TDK;WALSIN;DARFON;PHYCOMP | GRM155R71E153KA61D;C1005X7R1E153KT000F;0402B153K250CT;C1005X7R153KFT;223891715638 | Multiple |  | Purchase | SMT | 1 | PCS | C522 |
| 3 | B55.01102.M004 | 78.22322.2FL | CHIP CAP C 0.022U 25V K0402 X7R | R2_SA;HF_SA;G_SA; | MURATA;PHYCOMP;DARFON;WALSIN;YAGEO | GRM155R71E223KA61D;223891715641;C1005X7R223KFT;0402B223K250CT;CC0402KRX7R8BB223 | Multiple |  | Purchase | SMT | 1 | PCS | C737 |
| 3 | B55.01102.M004 | 78.22521.21L | CHIP CAP C 2.2UF 16V K0805 X7R | R2_SA;HF_SA;G_SA; | MURATA;TDK;TAIYO;DARFON;SAMSUNG;PHYCOMP;WALSIN | GRM21BR61C225KA88L;C2012X7R1C225KT000N;EMK212B7225KG-T;C2012X7R225KEP;CL21B225KOFNNNE;222278015667;0805B225K160CT | Multiple |  | Purchase | SMT | 1 | PCS | C739 |
| 3 | B55.01102.M004 | 78.47124.2FL | CHIP CAP C 470P  50V K0402 X7R | R2_SA;HF_SA;G_SA; | AVX;DARFON;MURATA;PHYCOMP;TAIYO;SAMSUNG;WALSIN;YAGEO | 04025C471KAT2A;C1005X7R471KGT;GRM155R71H471KA01D;223858715618;UMK105B7471KV-F;CL05B471KB5NNNC;0402B471K500CT;CC0402KRX7R9BB471 | Multiple |  | Purchase | SMT | 1 | PCS | C602 |
| 3 | B55.01102.M004 | 79.47719.2BL | CHIP CAP 470UF 2V EEFSX0D471X | R2_SA;HF_SA;G_SA; | PANASONIC | EEFSX0D471XE | Multiple |  | Purchase | SMT | 3 | PCS | TC1 TC2 TC3 |
| A | B55.01102.M004 | 077.54771.0001 | CHIP AP CAP 470UF 2V M7343 ESR6 | R2_SA;HF_SA; | APAQ | ACAH2R0S471E06 |  |  | Purchase |  |  |  |  |
| 3 | B55.01102.M004 | 83.01921.S70 | LED YEL GRN 19-21/G6C-BM2P1B/3T SMD | R2_SA;HF_SA;G_SA; | EVERLIGHT | 19-21/G6C-BM2P1B/3T | Multiple |  | Purchase | SMT | 1 | PCS | BLED1 |
| A | B55.01102.M004 | 83.19213.I70 | LED GRN 19-213/G6C-DH1J2AX/3T | R2_SA;HF_SA;G_SA; | EVERLIGHT | 19-213/G6C-DH1J2AX/3T |  |  | Purchase |  |  |  |  |
| 3 | B55.01102.M004 | 83.SMF15.0AH | DIODE TVS SMF15A SOD-123FL | R2_SA;HF_SA; | PANJIT | SMF15A | Multiple |  | Purchase | SMT | 1 | PCS | D37 |
| A | B55.01102.M004 | 83.00015.0AF | DIODE TVS DFLT15A-7 POWERDI123 | R2_SA;HF_SA; | DIODES | DFLT15A-7 |  |  | Purchase |  |  |  |  |
| 3 | B55.01102.M004 | 84.03904.T11 | XTOR MMBT3904 NPN SOT-23 | R2_SA;HF_SA;G_SA; | PANJIT | MMBT3904 | Multiple |  | Purchase | SMT | 1 | PCS | Q37 |
| A | B55.01102.M004 | 84.T3904.H11 | XTOR LMBT3904LT1G NPN SOT-23 | R2_SA;HF_SA;G_SA; | LRC | LMBT3904LT1G |  |  | Purchase |  |  |  |  |
| 3 | B55.01102.M004 | 84.2N702.031 | FET MOS 2N7002K-7 NC SOT-23 2KV 300MA | R2_SA;HF_SA; | DIODES | 2N7002K-7 | Multiple |  | Purchase | SMT | 2 | PCS | Q14 Q20 |
| A | B55.01102.M004 | 84.2N702.J31 | FET MOS 2N7002K NC SOT-23 ESD 2KV 300MA | R2_SA;HF_SA;G_SA; | PANJIT | 2N7002K |  |  | Purchase |  |  |  |  |
| 3 | B55.01102.M004 | B48.01121.0011 | PCB 16316-1 BRYCE CANYON SCC CARD 8L GCE | R2_SA;HF_SA; | GCE | B48.01121.0011 | Multiple |  | Purchase | SMT | 1 | PCS |  |
| A | B55.01102.M004 | B48.01146.0011 | PCB 16316-1 BRYCE CANYON SCC CARD 8L TRI | R2_SA;HF_SA; | TRIPOD | B48.01146.0011 |  |  | Purchase |  |  |  |  |
| 3 | B55.01102.M004 | BZA.01101.0050 | BRYCE CANYON EXP FW MODULE2 | R2; |  |  |  | M | Manufacture | SMT | 1 | PCS | FW |
| 4 | BZA.01101.0050 | 072.29128.0F09 | IC FEROM MX29GL128FDT2I-11G TSOP 56P | R2_SA;HF_SA; | MXIC | MX29GL128FDT2I-11G | Multiple |  | Purchase |  | 1 | PCS | U13 |
| A | BZA.01101.0050 | 72.29128.Z09 | IC FEROM S29GL128S10TFIV20 TSOP 56P | R2_SA;HF_SA; | SPANSION | S29GL128S10TFIV20 |  |  | Purchase |  |  |  |  |
| 4 | BZA.01101.0050 | B53.01101.00D1 | F/W BC EXPANDER 27.14.00.10_03 | R2; | TBD |  | Single |  | Manufacture |  | 1 | PCS |  |
| 2 | B55.01102.0004 | YAS0-00054-000$001 | SCREW TAPPING PAN M2 L5 BLUE ZN CR3+ | R2_SA;HF_SA; | WENHAO | TBD | Single |  | Purchase | DIP | 2 | PCS |  |
